(kicad_pcb
	(version 20260206)
	(generator "pcbnew")
	(generator_version "10.0")
	(general
		(thickness 1.6)
		(legacy_teardrops no)
	)
	(paper "A4")
	(title_block
		(title "Wiwynn_Tioga_Pass_MB.brd")
		(comment 1 "Tioga Pass / footprint 190 of 4770 (U2D1), pads 3596-3647 of 3647")
	)
	(layers
		(0 "F.Cu" signal "TOP")
		(4 "In1.Cu" signal "L2GND")
		(6 "In2.Cu" signal "L3")
		(8 "In3.Cu" signal "L4GND")
		(10 "In4.Cu" signal "L5")
		(12 "In5.Cu" signal "L6GND")
		(14 "In6.Cu" signal "L7VCC")
		(16 "In7.Cu" signal "L8VCC")
		(18 "In8.Cu" signal "L9GND")
		(20 "In9.Cu" signal "L10")
		(22 "In10.Cu" signal "L11GND")
		(24 "In11.Cu" signal "L12")
		(26 "In12.Cu" signal "L13GND")
		(2 "B.Cu" signal "BOTTOM")
		(9 "F.Adhes" user "F.Adhesive")
		(11 "B.Adhes" user "B.Adhesive")
		(13 "F.Paste" user "Package Geometry/Pastemask Top")
		(15 "B.Paste" user "Package Geometry/Pastemask Bottom")
		(5 "F.SilkS" user "Ref Des/Silkscreen Top")
		(7 "B.SilkS" user "Ref Des/Silkscreen Bottom")
		(1 "F.Mask" user "Board Geometry/Soldermask Top")
		(3 "B.Mask" user "Board Geometry/Soldermask Bottom")
		(17 "Dwgs.User" user "User.Drawings")
		(19 "Cmts.User" user "User.Comments")
		(21 "Eco1.User" user "User.Eco1")
		(23 "Eco2.User" user "User.Eco2")
		(25 "Edge.Cuts" user "Board Geometry/Outline")
		(27 "Margin" user)
		(31 "F.CrtYd" user "Package Geometry/Place Bound Top")
		(29 "B.CrtYd" user "Package Geometry/Place Bound Bottom")
		(35 "F.Fab" user "Ref Des/Assembly Top")
		(33 "B.Fab" user "Ref Des/Assembly Bottom")
	)
	(footprint ""
		(layer "F.Cu")
		(at 104.99979 -76.550012 180)
		(property "Reference" "U2D1"
			(at 25.19299 30.484318 0)
			(unlocked yes)
			(layer "F.SilkS")
			(effects
				(font
					(size 0.7874 0.5842)
					(thickness 0.1524)
				)
			)
		)
		(property "Value" ""
			(at 0 0 180)
			(layer "F.Fab")
			(effects
				(font
					(size 1.27 1.27)
				)
			)
		)
		(duplicate_pad_numbers_are_jumpers no)
		(pad "W70" smd circle
			(at 23.514558 -17.988026)
			(size 0.4318 0.4318)
			(layers "F.Cu" "F.Mask" "F.Paste")
			(net "M_J_DQS_DP<2>")
		)
		(pad "W72" smd circle
			(at 25.231598 -17.988026)
			(size 0.4318 0.4318)
			(layers "F.Cu" "F.Mask" "F.Paste")
			(net "M_J_DQ<16>")
		)
		(pad "W74" smd circle
			(at 26.948384 -17.988026)
			(size 0.4318 0.4318)
			(layers "F.Cu" "F.Mask" "F.Paste")
			(net "GND")
		)
		(pad "W76" smd circle
			(at 28.665424 -17.988026)
			(size 0.4318 0.4318)
			(layers "F.Cu" "F.Mask" "F.Paste")
			(net "M_J_DQ<11>")
		)
		(pad "W78" smd circle
			(at 30.382464 -17.988026)
			(size 0.4318 0.4318)
			(layers "F.Cu" "F.Mask" "F.Paste")
			(net "GND")
		)
		(pad "W80" smd circle
			(at 32.099504 -17.988026)
			(size 0.4318 0.4318)
			(layers "F.Cu" "F.Mask" "F.Paste")
			(net "M_G_DQ<20>")
		)
		(pad "W82" smd circle
			(at 33.816544 -17.988026)
			(size 0.4318 0.4318)
			(layers "F.Cu" "F.Mask" "F.Paste")
			(net "GND")
		)
		(pad "W84" smd circle
			(at 35.533584 -17.988026)
			(size 0.4318 0.4318)
			(layers "F.Cu" "F.Mask" "F.Paste")
			(net "M_G_DQ<9>")
		)
		(pad "W86" smd custom
			(at 37.250624 -17.988026 270)
			(size 0.10795 0.10795)
			(layers "F.Cu" "F.Mask" "F.Paste")
			(net "M_G_DQ<8>")
			(options
				(clearance outline)
				(anchor circle)
			)
			(primitives
				(gr_poly
					(pts
						(arc
							(start 0.2159 -0.0381)
							(mid 0 -0.254)
							(end -0.2159 -0.0381)
						)
						(arc
							(start -0.2159 0.0381)
							(mid 0 0.254)
							(end 0.2159 0.0381)
						)
					)
					(width 0)
					(fill yes)
				)
			)
		)
		(pad "Y1" smd custom
			(at -37.250624 -15.692628 90)
			(size 0.10795 0.10795)
			(layers "F.Cu" "F.Mask" "F.Paste")
			(net "UPI_CPU1_CPU0_P0P0_DN<3>")
			(options
				(clearance outline)
				(anchor circle)
			)
			(primitives
				(gr_poly
					(pts
						(arc
							(start 0.2159 -0.0381)
							(mid 0 -0.254)
							(end -0.2159 -0.0381)
						)
						(arc
							(start -0.2159 0.0381)
							(mid 0 0.254)
							(end 0.2159 0.0381)
						)
					)
					(width 0)
					(fill yes)
				)
			)
		)
		(pad "Y3" smd circle
			(at -35.533584 -15.692628)
			(size 0.4318 0.4318)
			(layers "F.Cu" "F.Mask" "F.Paste")
			(net "UPI_CPU1_CPU0_P0P0_DP<2>")
		)
		(pad "Y5" smd circle
			(at -33.816544 -15.692628)
			(size 0.4318 0.4318)
			(layers "F.Cu" "F.Mask" "F.Paste")
			(net "GND")
		)
		(pad "Y7" smd circle
			(at -32.099504 -15.692628)
			(size 0.4318 0.4318)
			(layers "F.Cu" "F.Mask" "F.Paste")
			(net "GND")
		)
		(pad "Y9" smd circle
			(at -30.382464 -15.692628)
			(size 0.4318 0.4318)
			(layers "F.Cu" "F.Mask" "F.Paste")
			(net "GND")
		)
		(pad "Y11" smd circle
			(at -28.665424 -15.692628)
			(size 0.4318 0.4318)
			(layers "F.Cu" "F.Mask" "F.Paste")
			(net "TP_XDP_CPU1_OBSDATA_B3_MBP5_N")
		)
		(pad "Y13" smd circle
			(at -26.948384 -15.692628)
			(size 0.4318 0.4318)
			(layers "F.Cu" "F.Mask" "F.Paste")
			(net "XDP_CPU_TRST_N")
		)
		(pad "Y15" smd circle
			(at -25.231598 -15.692628)
			(size 0.4318 0.4318)
			(layers "F.Cu" "F.Mask" "F.Paste")
			(net "GND")
		)
		(pad "Y17" smd circle
			(at -23.514558 -15.692628)
			(size 0.4318 0.4318)
			(layers "F.Cu" "F.Mask" "F.Paste")
			(net "GND")
		)
		(pad "Y19" smd circle
			(at -21.797518 -15.692628)
			(size 0.4318 0.4318)
			(layers "F.Cu" "F.Mask" "F.Paste")
			(net "UPI_CPU0_CPU1_P1P1_DP<17>")
		)
		(pad "Y21" smd circle
			(at -20.080478 -15.692628)
			(size 0.4318 0.4318)
			(layers "F.Cu" "F.Mask" "F.Paste")
			(net "UPI_CPU0_CPU1_P1P1_DP<18>")
		)
		(pad "Y23" smd circle
			(at -18.363438 -15.692628)
			(size 0.4318 0.4318)
			(layers "F.Cu" "F.Mask" "F.Paste")
			(net "FM_CPU1_RC_ERROR_N")
		)
		(pad "Y25" smd circle
			(at -16.646398 -15.692628)
			(size 0.4318 0.4318)
			(layers "F.Cu" "F.Mask" "F.Paste")
			(net "M_H_DQ<59>")
		)
		(pad "Y27" smd circle
			(at -14.929612 -15.692628)
			(size 0.4318 0.4318)
			(layers "F.Cu" "F.Mask" "F.Paste")
			(net "M_H_DQS_DP<7>")
		)
		(pad "Y29" smd circle
			(at -13.212572 -15.692628)
			(size 0.4318 0.4318)
			(layers "F.Cu" "F.Mask" "F.Paste")
			(net "M_H_DQ<61>")
		)
		(pad "Y31" smd circle
			(at -11.495532 -15.692628)
			(size 0.4318 0.4318)
			(layers "F.Cu" "F.Mask" "F.Paste")
			(net "M_J_DQ<43>")
		)
		(pad "Y33" smd circle
			(at -9.778492 -15.692628)
			(size 0.4318 0.4318)
			(layers "F.Cu" "F.Mask" "F.Paste")
			(net "M_J_DQS_DP<5>")
		)
		(pad "Y35" smd circle
			(at -8.061452 -15.692628)
			(size 0.4318 0.4318)
			(layers "F.Cu" "F.Mask" "F.Paste")
			(net "M_J_DQ<45>")
		)
		(pad "Y37" smd circle
			(at -6.344412 -15.692628)
			(size 0.4318 0.4318)
			(layers "F.Cu" "F.Mask" "F.Paste")
			(net "M_J_DQ<35>")
		)
		(pad "Y39" smd circle
			(at -4.627626 -15.692628)
			(size 0.4318 0.4318)
			(layers "F.Cu" "F.Mask" "F.Paste")
			(net "M_J_DQS_DP<4>")
		)
		(pad "Y41" smd circle
			(at -2.910586 -15.692628)
			(size 0.4318 0.4318)
			(layers "F.Cu" "F.Mask" "F.Paste")
			(net "M_J_DQ<37>")
		)
		(pad "Y43" smd circle
			(at -1.193546 -15.692628)
			(size 0.4318 0.4318)
			(layers "F.Cu" "F.Mask" "F.Paste")
			(net "A_CPU1_GHJ_RCOMP0")
		)
		(pad "Y45" smd circle
			(at 2.052066 -17.492726)
			(size 0.508 0.508)
			(layers "F.Cu" "F.Mask" "F.Paste")
			(net "PVDDQ_GHJ")
		)
		(pad "Y47" smd circle
			(at 3.769106 -17.492726)
			(size 0.4318 0.4318)
			(layers "F.Cu" "F.Mask" "F.Paste")
			(net "PVDDQ_GHJ")
		)
		(pad "Y49" smd circle
			(at 5.485892 -17.492726)
			(size 0.4318 0.4318)
			(layers "F.Cu" "F.Mask" "F.Paste")
			(net "PVDDQ_GHJ")
		)
		(pad "Y51" smd circle
			(at 7.202932 -17.492726)
			(size 0.4318 0.4318)
			(layers "F.Cu" "F.Mask" "F.Paste")
			(net "PVDDQ_GHJ")
		)
		(pad "Y53" smd circle
			(at 8.919972 -17.492726)
			(size 0.4318 0.4318)
			(layers "F.Cu" "F.Mask" "F.Paste")
			(net "PVDDQ_GHJ")
		)
		(pad "Y55" smd circle
			(at 10.637012 -17.492726)
			(size 0.4318 0.4318)
			(layers "F.Cu" "F.Mask" "F.Paste")
			(net "PVDDQ_GHJ")
		)
		(pad "Y57" smd circle
			(at 12.354052 -17.492726)
			(size 0.4318 0.4318)
			(layers "F.Cu" "F.Mask" "F.Paste")
			(net "PVDDQ_GHJ")
		)
		(pad "Y59" smd circle
			(at 14.071092 -17.492726)
			(size 0.4318 0.4318)
			(layers "F.Cu" "F.Mask" "F.Paste")
			(net "PVDDQ_GHJ")
		)
		(pad "Y61" smd circle
			(at 15.787878 -17.492726)
			(size 0.4318 0.4318)
			(layers "F.Cu" "F.Mask" "F.Paste")
			(net "PVDDQ_GHJ")
		)
		(pad "Y63" smd circle
			(at 17.504918 -17.492726)
			(size 0.4318 0.4318)
			(layers "F.Cu" "F.Mask" "F.Paste")
			(net "PVDDQ_GHJ")
		)
		(pad "Y65" smd circle
			(at 19.221958 -17.492726)
			(size 0.4318 0.4318)
			(layers "F.Cu" "F.Mask" "F.Paste")
			(net "TP_CPU1_RSVD_256")
		)
		(pad "Y67" smd circle
			(at 20.938998 -17.492726)
			(size 0.4318 0.4318)
			(layers "F.Cu" "F.Mask" "F.Paste")
			(net "GND")
		)
		(pad "Y69" smd circle
			(at 22.656038 -17.492726)
			(size 0.4318 0.4318)
			(layers "F.Cu" "F.Mask" "F.Paste")
			(net "M_J_DQS_DN<2>")
		)
		(pad "Y71" smd circle
			(at 24.373078 -17.492726)
			(size 0.4318 0.4318)
			(layers "F.Cu" "F.Mask" "F.Paste")
			(net "GND")
		)
		(pad "Y73" smd circle
			(at 26.090118 -17.492726)
			(size 0.4318 0.4318)
			(layers "F.Cu" "F.Mask" "F.Paste")
			(net "GND")
		)
		(pad "Y75" smd circle
			(at 27.806904 -17.492726)
			(size 0.4318 0.4318)
			(layers "F.Cu" "F.Mask" "F.Paste")
			(net "M_J_DQ<15>")
		)
		(pad "Y77" smd circle
			(at 29.523944 -17.492726)
			(size 0.4318 0.4318)
			(layers "F.Cu" "F.Mask" "F.Paste")
			(net "M_J_DQ<10>")
		)
		(pad "Y79" smd circle
			(at 31.240984 -17.492726)
			(size 0.4318 0.4318)
			(layers "F.Cu" "F.Mask" "F.Paste")
			(net "GND")
		)
		(pad "Y81" smd circle
			(at 32.958024 -17.492726)
			(size 0.4318 0.4318)
			(layers "F.Cu" "F.Mask" "F.Paste")
			(net "GND")
		)
		(pad "Y83" smd circle
			(at 34.675064 -17.492726)
			(size 0.4318 0.4318)
			(layers "F.Cu" "F.Mask" "F.Paste")
			(net "GND")
		)
		(pad "Y85" smd circle
			(at 36.392104 -17.492726)
			(size 0.4318 0.4318)
			(layers "F.Cu" "F.Mask" "F.Paste")
			(net "GND")
		)
	)
)
